FILE_TYPE = MACRO_DRAWING;
SET COLOR_WIRE YELLOW;
SET COLOR_PROP ORANGE;
SET COLOR_DOT WHITE;
SET COLOR_ARC YELLOW;
SET COLOR_BODY GREEN;
SET COLOR_NOTE PURPLE;
SET PROP_DISPLAY VALUE;
SET PAGE_NUMBER P1;
SET PATH_NUMBER P0;
FORCEADD QUANTA_TITLE_BLOCK_C..1
(6275 -1825);
FORCEPROP 0 LAST CDS_CON_LAST_MODIFIED Fri Aug 25 17:25:34 2023
J 0
(4390 -1810);
DISPLAY INVISIBLE (4390 -1810);
FORCEPROP 1 LAST CUSTOM_TXT_CDS <Q_NUMBER>
J 0
(4872 -1722);
DISPLAY 1.212766 (4872 -1722);
FORCEPROP 1 LAST CUSTOM_TXT_CDS <Q_PROJ>
J 0
(3893 -1723);
DISPLAY 1.212766 (3893 -1723);
FORCEPROP 1 LAST CUSTOM_TXT_CDS <Q_REV>
J 0
(6091 -1722);
DISPLAY 1.212766 (6091 -1722);
FORCEPROP 2 LAST Q_DEPT 
J 1
(2512 -1776);
DISPLAY 1.957447 (2512 -1776);
PAINT GREEN (2512 -1776);
FORCEPROP 1 LAST CUSTOM_TXT_CDS <NAME_2>
J 0
(3100 -1775);
FORCEPROP 1 LAST CUSTOM_TXT_CDS <NAME_1>
J 0
(3100 -1650);
FORCEPROP 1 LAST CUSTOM_TXT_CDS <CON_LAST_MODIFIED>
J 0
(4390 -1810);
DISPLAY 0.978723 (4390 -1810);
FORCEPROP 1 LAST CUSTOM_TXT_CDS <CON_PAGE_NUM> OF <CON_TOTAL_PAGES>
J 0
(5829 -1807);
DISPLAY 0.978723 (5829 -1807);
FORCEPROP 2 LAST CUSTOM_TXT_CDS <XR_PAGE_TITLE>
J 0
(-1615 3425);
DISPLAY 0.638298 (-1615 3425);
PAINT PINK (-1615 3425);
DISPLAY INVISIBLE (-1615 3425);
FORCEPROP 1 LAST Q_TITLE TITLE
J 0
(-3091 -1799);
DISPLAY 2.446809 (-3091 -1799);
PAINT GREEN (-3091 -1799);
FORCEPROP 2 LAST CDS_XR_PAGE_TITLE CR-1 : @SCM_LIB.SCM(SCH_1):PAGE1
J 0
(-1615 3425);
DISPLAY 0.638298 (-1615 3425);
PAINT PINK (-1615 3425);
DISPLAY INVISIBLE (-1615 3425);
FORCEPROP 2 LAST PAGE_BORDER TRUE
J 0
(-1615 3425);
DISPLAY 0.638298 (-1615 3425);
PAINT PINK (-1615 3425);
DISPLAY INVISIBLE (-1615 3425);
FORCEPROP 1 LAST CDS_LMAN_SYM_OUTLINE -9475,6775,100,-125
J 0
(6275 -1825);
DISPLAY 0.468085 (6275 -1825);
PAINT GREEN (6275 -1825);
DISPLAY INVISIBLE (6275 -1825);
FORCEPROP 2 LAST CDS_LIB pure_quanta
J 0
(6275 -1825);
DISPLAY INVISIBLE (6275 -1825);
FORCEPROP 1 LAST COMMENT_BODY TRUE
J 0
(6287 -1838);
DISPLAY 0.978723 (6287 -1838);
PAINT PEACH (6287 -1838);
DISPLAY INVISIBLE (6287 -1838);
FORCENOTE
SYSTEM CONTROL MANAGEMENT
(-2425 2475) 0;
DISPLAY LEFT (-2425 2475);
DISPLAY 6.978724 (-2425 2475);
PAINT WHITE (-2425 2475);
FORCENOTE
GRAND TETON
(-400 2975) 0;
DISPLAY LEFT (-400 2975);
DISPLAY 6.978724 (-400 2975);
PAINT WHITE (-400 2975);
QUIT
